(kicad_pcb
	(version 20260206)
	(generator "pcbnew")
	(generator_version "10.0")
	(general
		(thickness 1.6)
		(legacy_teardrops no)
	)
	(paper "A4")
	(title_block
		(title "03242023_DA0F0TMBIJ0_F0T_Motherboard_J_brd_V01_OCP.brd")
		(comment 1 "Grand Teton / footprint 1607 of 6105 (J10), pads 225-291 of 291")
	)
	(layers
		(0 "F.Cu" signal "TOP")
		(4 "In1.Cu" signal "GND")
		(6 "In2.Cu" signal "IN1")
		(8 "In3.Cu" signal "GND1")
		(10 "In4.Cu" signal "IN2")
		(12 "In5.Cu" signal "GND2")
		(14 "In6.Cu" signal "IN3")
		(16 "In7.Cu" signal "GND3")
		(18 "In8.Cu" signal "VCC")
		(20 "In9.Cu" signal "VCC1")
		(22 "In10.Cu" signal "GND4")
		(24 "In11.Cu" signal "IN4")
		(26 "In12.Cu" signal "GND5")
		(28 "In13.Cu" signal "IN5")
		(30 "In14.Cu" signal "GND6")
		(32 "In15.Cu" signal "IN6")
		(34 "In16.Cu" signal "GND7")
		(2 "B.Cu" signal "BOTTOM")
		(9 "F.Adhes" user "F.Adhesive")
		(11 "B.Adhes" user "B.Adhesive")
		(13 "F.Paste" user "Package Geometry/Pastemask Top")
		(15 "B.Paste" user "Package Geometry/Pastemask Bottom")
		(5 "F.SilkS" user "Ref Des/Silkscreen Top")
		(7 "B.SilkS" user "Ref Des/Silkscreen Bottom")
		(1 "F.Mask" user "Board Geometry/Soldermask Top")
		(3 "B.Mask" user "Board Geometry/Soldermask Bottom")
		(17 "Dwgs.User" user "User.Drawings")
		(19 "Cmts.User" user "User.Comments")
		(21 "Eco1.User" user "User.Eco1")
		(23 "Eco2.User" user "User.Eco2")
		(25 "Edge.Cuts" user "Board Geometry/Outline")
		(27 "Margin" user)
		(31 "F.CrtYd" user "Package Geometry/Place Bound Top")
		(29 "B.CrtYd" user "Package Geometry/Place Bound Bottom")
		(35 "F.Fab" user "Ref Des/Assembly Top")
		(33 "B.Fab" user "Ref Des/Assembly Bottom")
	)
	(footprint ""
		(layer "F.Cu")
		(at 408.803348 -258.091686)
		(property "Reference" "J10"
			(at -3.683 -81.702148 0)
			(unlocked yes)
			(layer "F.SilkS")
			(effects
				(font
					(size 0.7874 0.5842)
					(thickness 0.1524)
				)
				(justify left)
			)
		)
		(property "Value" ""
			(at 0 0 0)
			(layer "F.Fab")
			(effects
				(font
					(size 1.27 1.27)
				)
			)
		)
		(duplicate_pad_numbers_are_jumpers no)
		(pad "225" smd rect
			(at 2.050034 9.774936 270)
			(size 0.519938 1.4986)
			(layers "F.Cu" "F.Mask" "F.Paste")
			(net "M_E_CPU0_SB_CA<5>")
		)
		(pad "226" smd rect
			(at 2.050034 10.625074 270)
			(size 0.519938 1.4986)
			(layers "F.Cu" "F.Mask" "F.Paste")
			(net "GND")
		)
		(pad "227" smd rect
			(at 2.050034 11.474958 270)
			(size 0.519938 1.4986)
			(layers "F.Cu" "F.Mask" "F.Paste")
			(net "M_E_CPU0_SB_PAR")
		)
		(pad "228" smd rect
			(at 2.050034 12.325096 270)
			(size 0.519938 1.4986)
			(layers "F.Cu" "F.Mask" "F.Paste")
			(net "GND")
		)
		(pad "229" smd rect
			(at 2.050034 13.17498 270)
			(size 0.519938 1.4986)
			(layers "F.Cu" "F.Mask" "F.Paste")
			(net "M_E_CPU0_SB_CS_N<3>")
		)
		(pad "230" smd rect
			(at 2.050034 14.025118 270)
			(size 0.519938 1.4986)
			(layers "F.Cu" "F.Mask" "F.Paste")
			(net "GND")
		)
		(pad "231" smd rect
			(at 2.050034 14.875002 270)
			(size 0.519938 1.4986)
			(layers "F.Cu" "F.Mask" "F.Paste")
			(net "TP_CHE_CPU0_DIMM2_FRU_5")
		)
		(pad "232" smd rect
			(at 2.050034 15.724886 270)
			(size 0.519938 1.4986)
			(layers "F.Cu" "F.Mask" "F.Paste")
			(net "TP_CHE_CPU0_DIMM2_FRU_6")
		)
		(pad "233" smd rect
			(at 2.050034 16.575024 270)
			(size 0.519938 1.4986)
			(layers "F.Cu" "F.Mask" "F.Paste")
			(net "GND")
		)
		(pad "234" smd rect
			(at 2.050034 17.424908 270)
			(size 0.519938 1.4986)
			(layers "F.Cu" "F.Mask" "F.Paste")
			(net "M_E_CPU0_SB_CB<6>")
		)
		(pad "235" smd rect
			(at 2.050034 18.275046 270)
			(size 0.519938 1.4986)
			(layers "F.Cu" "F.Mask" "F.Paste")
			(net "GND")
		)
		(pad "236" smd rect
			(at 2.050034 19.12493 270)
			(size 0.519938 1.4986)
			(layers "F.Cu" "F.Mask" "F.Paste")
			(net "M_E_CPU0_SB_CB<7>")
		)
		(pad "237" smd rect
			(at 2.050034 19.975068 270)
			(size 0.519938 1.4986)
			(layers "F.Cu" "F.Mask" "F.Paste")
			(net "GND")
		)
		(pad "238" smd rect
			(at 2.050034 20.824952 270)
			(size 0.519938 1.4986)
			(layers "F.Cu" "F.Mask" "F.Paste")
			(net "M_E_CPU0_SB_DQS_DN<4>")
		)
		(pad "239" smd rect
			(at 2.050034 21.67509 270)
			(size 0.519938 1.4986)
			(layers "F.Cu" "F.Mask" "F.Paste")
			(net "M_E_CPU0_SB_DQS_DP<4>")
		)
		(pad "240" smd rect
			(at 2.050034 22.524974 270)
			(size 0.519938 1.4986)
			(layers "F.Cu" "F.Mask" "F.Paste")
			(net "GND")
		)
		(pad "241" smd rect
			(at 2.050034 23.375112 270)
			(size 0.519938 1.4986)
			(layers "F.Cu" "F.Mask" "F.Paste")
			(net "M_E_CPU0_SB_CB<2>")
		)
		(pad "242" smd rect
			(at 2.050034 24.224996 270)
			(size 0.519938 1.4986)
			(layers "F.Cu" "F.Mask" "F.Paste")
			(net "GND")
		)
		(pad "243" smd rect
			(at 2.050034 25.07488 270)
			(size 0.519938 1.4986)
			(layers "F.Cu" "F.Mask" "F.Paste")
			(net "M_E_CPU0_SB_CB<3>")
		)
		(pad "244" smd rect
			(at 2.050034 25.925018 270)
			(size 0.519938 1.4986)
			(layers "F.Cu" "F.Mask" "F.Paste")
			(net "GND")
		)
		(pad "245" smd rect
			(at 2.050034 26.774902 270)
			(size 0.519938 1.4986)
			(layers "F.Cu" "F.Mask" "F.Paste")
			(net "M_E_CPU0_SB_DQ<2>")
		)
		(pad "246" smd rect
			(at 2.050034 27.62504 270)
			(size 0.519938 1.4986)
			(layers "F.Cu" "F.Mask" "F.Paste")
			(net "GND")
		)
		(pad "247" smd rect
			(at 2.050034 28.474924 270)
			(size 0.519938 1.4986)
			(layers "F.Cu" "F.Mask" "F.Paste")
			(net "M_E_CPU0_SB_DQ<3>")
		)
		(pad "248" smd rect
			(at 2.050034 29.325062 270)
			(size 0.519938 1.4986)
			(layers "F.Cu" "F.Mask" "F.Paste")
			(net "GND")
		)
		(pad "249" smd rect
			(at 2.050034 30.174946 270)
			(size 0.519938 1.4986)
			(layers "F.Cu" "F.Mask" "F.Paste")
			(net "M_E_CPU0_SB_DQS_DN<5>")
		)
		(pad "250" smd rect
			(at 2.050034 31.025084 270)
			(size 0.519938 1.4986)
			(layers "F.Cu" "F.Mask" "F.Paste")
			(net "M_E_CPU0_SB_DQS_DP<5>")
		)
		(pad "251" smd rect
			(at 2.050034 31.874968 270)
			(size 0.519938 1.4986)
			(layers "F.Cu" "F.Mask" "F.Paste")
			(net "GND")
		)
		(pad "252" smd rect
			(at 2.050034 32.725106 270)
			(size 0.519938 1.4986)
			(layers "F.Cu" "F.Mask" "F.Paste")
			(net "M_E_CPU0_SB_DQ<6>")
		)
		(pad "253" smd rect
			(at 2.050034 33.57499 270)
			(size 0.519938 1.4986)
			(layers "F.Cu" "F.Mask" "F.Paste")
			(net "GND")
		)
		(pad "254" smd rect
			(at 2.050034 34.425128 270)
			(size 0.519938 1.4986)
			(layers "F.Cu" "F.Mask" "F.Paste")
			(net "M_E_CPU0_SB_DQ<7>")
		)
		(pad "255" smd rect
			(at 2.050034 35.275012 270)
			(size 0.519938 1.4986)
			(layers "F.Cu" "F.Mask" "F.Paste")
			(net "GND")
		)
		(pad "256" smd rect
			(at 2.050034 36.124896 270)
			(size 0.519938 1.4986)
			(layers "F.Cu" "F.Mask" "F.Paste")
			(net "M_E_CPU0_SB_DQ<10>")
		)
		(pad "257" smd rect
			(at 2.050034 36.975034 270)
			(size 0.519938 1.4986)
			(layers "F.Cu" "F.Mask" "F.Paste")
			(net "GND")
		)
		(pad "258" smd rect
			(at 2.050034 37.824918 270)
			(size 0.519938 1.4986)
			(layers "F.Cu" "F.Mask" "F.Paste")
			(net "M_E_CPU0_SB_DQ<11>")
		)
		(pad "259" smd rect
			(at 2.050034 38.675056 270)
			(size 0.519938 1.4986)
			(layers "F.Cu" "F.Mask" "F.Paste")
			(net "GND")
		)
		(pad "260" smd rect
			(at 2.050034 39.52494 270)
			(size 0.519938 1.4986)
			(layers "F.Cu" "F.Mask" "F.Paste")
			(net "M_E_CPU0_SB_DQS_DN<6>")
		)
		(pad "261" smd rect
			(at 2.050034 40.375078 270)
			(size 0.519938 1.4986)
			(layers "F.Cu" "F.Mask" "F.Paste")
			(net "M_E_CPU0_SB_DQS_DP<6>")
		)
		(pad "262" smd rect
			(at 2.050034 41.224962 270)
			(size 0.519938 1.4986)
			(layers "F.Cu" "F.Mask" "F.Paste")
			(net "GND")
		)
		(pad "263" smd rect
			(at 2.050034 42.0751 270)
			(size 0.519938 1.4986)
			(layers "F.Cu" "F.Mask" "F.Paste")
			(net "M_E_CPU0_SB_DQ<14>")
		)
		(pad "264" smd rect
			(at 2.050034 42.924984 270)
			(size 0.519938 1.4986)
			(layers "F.Cu" "F.Mask" "F.Paste")
			(net "GND")
		)
		(pad "265" smd rect
			(at 2.050034 43.775122 270)
			(size 0.519938 1.4986)
			(layers "F.Cu" "F.Mask" "F.Paste")
			(net "M_E_CPU0_SB_DQ<15>")
		)
		(pad "266" smd rect
			(at 2.050034 44.625006 270)
			(size 0.519938 1.4986)
			(layers "F.Cu" "F.Mask" "F.Paste")
			(net "GND")
		)
		(pad "267" smd rect
			(at 2.050034 45.47489 270)
			(size 0.519938 1.4986)
			(layers "F.Cu" "F.Mask" "F.Paste")
			(net "M_E_CPU0_SB_DQ<18>")
		)
		(pad "268" smd rect
			(at 2.050034 46.325028 270)
			(size 0.519938 1.4986)
			(layers "F.Cu" "F.Mask" "F.Paste")
			(net "GND")
		)
		(pad "269" smd rect
			(at 2.050034 47.174912 270)
			(size 0.519938 1.4986)
			(layers "F.Cu" "F.Mask" "F.Paste")
			(net "M_E_CPU0_SB_DQ<19>")
		)
		(pad "270" smd rect
			(at 2.050034 48.02505 270)
			(size 0.519938 1.4986)
			(layers "F.Cu" "F.Mask" "F.Paste")
			(net "GND")
		)
		(pad "271" smd rect
			(at 2.050034 48.874934 270)
			(size 0.519938 1.4986)
			(layers "F.Cu" "F.Mask" "F.Paste")
			(net "M_E_CPU0_SB_DQS_DN<7>")
		)
		(pad "272" smd rect
			(at 2.050034 49.725072 270)
			(size 0.519938 1.4986)
			(layers "F.Cu" "F.Mask" "F.Paste")
			(net "M_E_CPU0_SB_DQS_DP<7>")
		)
		(pad "273" smd rect
			(at 2.050034 50.574956 270)
			(size 0.519938 1.4986)
			(layers "F.Cu" "F.Mask" "F.Paste")
			(net "GND")
		)
		(pad "274" smd rect
			(at 2.050034 51.425094 270)
			(size 0.519938 1.4986)
			(layers "F.Cu" "F.Mask" "F.Paste")
			(net "M_E_CPU0_SB_DQ<22>")
		)
		(pad "275" smd rect
			(at 2.050034 52.274978 270)
			(size 0.519938 1.4986)
			(layers "F.Cu" "F.Mask" "F.Paste")
			(net "GND")
		)
		(pad "276" smd rect
			(at 2.050034 53.125116 270)
			(size 0.519938 1.4986)
			(layers "F.Cu" "F.Mask" "F.Paste")
			(net "M_E_CPU0_SB_DQ<23>")
		)
		(pad "277" smd rect
			(at 2.050034 53.975 270)
			(size 0.519938 1.4986)
			(layers "F.Cu" "F.Mask" "F.Paste")
			(net "GND")
		)
		(pad "278" smd rect
			(at 2.050034 54.824884 270)
			(size 0.519938 1.4986)
			(layers "F.Cu" "F.Mask" "F.Paste")
			(net "M_E_CPU0_SB_DQ<26>")
		)
		(pad "279" smd rect
			(at 2.050034 55.675022 270)
			(size 0.519938 1.4986)
			(layers "F.Cu" "F.Mask" "F.Paste")
			(net "GND")
		)
		(pad "280" smd rect
			(at 2.050034 56.524906 270)
			(size 0.519938 1.4986)
			(layers "F.Cu" "F.Mask" "F.Paste")
			(net "M_E_CPU0_SB_DQ<27>")
		)
		(pad "281" smd rect
			(at 2.050034 57.375044 270)
			(size 0.519938 1.4986)
			(layers "F.Cu" "F.Mask" "F.Paste")
			(net "GND")
		)
		(pad "282" smd rect
			(at 2.050034 58.224928 270)
			(size 0.519938 1.4986)
			(layers "F.Cu" "F.Mask" "F.Paste")
			(net "M_E_CPU0_SB_DQS_DN<8>")
		)
		(pad "283" smd rect
			(at 2.050034 59.075066 270)
			(size 0.519938 1.4986)
			(layers "F.Cu" "F.Mask" "F.Paste")
			(net "M_E_CPU0_SB_DQS_DP<8>")
		)
		(pad "284" smd rect
			(at 2.050034 59.92495 270)
			(size 0.519938 1.4986)
			(layers "F.Cu" "F.Mask" "F.Paste")
			(net "GND")
		)
		(pad "285" smd rect
			(at 2.050034 60.775088 270)
			(size 0.519938 1.4986)
			(layers "F.Cu" "F.Mask" "F.Paste")
			(net "M_E_CPU0_SB_DQ<30>")
		)
		(pad "286" smd rect
			(at 2.050034 61.624972 270)
			(size 0.519938 1.4986)
			(layers "F.Cu" "F.Mask" "F.Paste")
			(net "GND")
		)
		(pad "287" smd rect
			(at 2.050034 62.47511 270)
			(size 0.519938 1.4986)
			(layers "F.Cu" "F.Mask" "F.Paste")
			(net "M_E_CPU0_SB_DQ<31>")
		)
		(pad "288" smd rect
			(at 2.050034 63.324994 270)
			(size 0.519938 1.4986)
			(layers "F.Cu" "F.Mask" "F.Paste")
			(net "GND")
		)
		(pad "G1" thru_hole oval
			(at 0 -68.97497)
			(size 2.8194 1.5748)
			(drill oval 2.4384 1.1938)
			(layers "*.Cu" "*.Mask")
			(remove_unused_layers no)
			(net "GND")
			(clearance 0.127)
			(thermal_gap 0.127)
		)
		(pad "G2" thru_hole oval
			(at 0 3.875024)
			(size 2.8194 1.5748)
			(drill oval 2.4384 1.1938)
			(layers "*.Cu" "*.Mask")
			(remove_unused_layers no)
			(net "GND")
			(clearance 0.127)
			(thermal_gap 0.127)
		)
		(pad "G3" thru_hole oval
			(at 0 68.97497)
			(size 2.8194 1.5748)
			(drill oval 2.4384 1.1938)
			(layers "*.Cu" "*.Mask")
			(remove_unused_layers no)
			(net "GND")
			(clearance 0.127)
			(thermal_gap 0.127)
		)
	)
)
